(kicad_pcb
	(version 20241229)
	(generator "pcbnew")
	(generator_version "9.0")
	(general
		(thickness 1.62)
		(legacy_teardrops no)
	)
	(paper "A3")
	(title_block
		(title "COM Express 7 Baseboard")
		(date "2025-02-04")
		(rev "1.1.2")
		(company "Antmicro Ltd")
		(comment 1 "www.antmicro.com")
		(comment 9 "footprints 258-262 of 802")
	)
	(layers
		(0 "F.Cu" signal)
		(4 "In1.Cu" signal)
		(6 "In2.Cu" signal)
		(8 "In3.Cu" signal)
		(10 "In4.Cu" signal)
		(12 "In5.Cu" signal)
		(14 "In6.Cu" signal)
		(2 "B.Cu" signal)
		(9 "F.Adhes" user "F.Adhesive")
		(11 "B.Adhes" user "B.Adhesive")
		(13 "F.Paste" user)
		(15 "B.Paste" user)
		(5 "F.SilkS" user "F.Silkscreen")
		(7 "B.SilkS" user "B.Silkscreen")
		(1 "F.Mask" user)
		(3 "B.Mask" user)
		(17 "Dwgs.User" user "User.Drawings")
		(19 "Cmts.User" user "User.Comments")
		(21 "Eco1.User" user "User.Eco1")
		(23 "Eco2.User" user "User.Eco2")
		(25 "Edge.Cuts" user)
		(27 "Margin" user)
		(31 "F.CrtYd" user "F.Courtyard")
		(29 "B.CrtYd" user "B.Courtyard")
		(35 "F.Fab" user)
		(33 "B.Fab" user)
	)
	(footprint "antmicro-footprints:R_0402_1005Metric"
		(layer "F.Cu")
		(at 222.68 128.2 180)
		(descr "Resistor SMD 0402")
		(tags "resistor SMD 0402")
		(property "Reference" "R317"
			(at -3.62 -0.41 0)
			(layer "F.SilkS")
			(effects
				(font
					(size 0.7 0.7)
					(thickness 0.15)
				)
				(justify right bottom)
			)
		)
		(property "Value" "R_0R_0402"
			(at -1.011843 1.772047 0)
			(layer "F.Fab")
			(effects
				(font
					(size 0.7 0.7)
					(thickness 0.15)
				)
				(justify right bottom)
			)
		)
		(property "Datasheet" "https://industrial.panasonic.com/cdbs/www-data/pdf/RDA0000/AOA0000C301.pdf"
			(at 0 0 180)
			(layer "F.Fab")
			(hide yes)
			(effects
				(font
					(size 1.27 1.27)
					(thickness 0.15)
				)
			)
		)
		(property "Author" "Antmicro"
			(at 445.36 256.4 0)
			(layer "F.Fab")
			(hide yes)
			(effects
				(font
					(size 1 1)
					(thickness 0.15)
				)
			)
		)
		(property "Current" "1A"
			(at 445.36 256.4 0)
			(layer "F.Fab")
			(hide yes)
			(effects
				(font
					(size 1 1)
					(thickness 0.15)
				)
			)
		)
		(property "License" "Apache-2.0"
			(at 445.36 256.4 0)
			(layer "F.Fab")
			(hide yes)
			(effects
				(font
					(size 1 1)
					(thickness 0.15)
				)
			)
		)
		(property "MPN" "ERJ2GE0R00X"
			(at 445.36 256.4 0)
			(layer "F.Fab")
			(hide yes)
			(effects
				(font
					(size 1 1)
					(thickness 0.15)
				)
			)
		)
		(property "Manufacturer" "Panasonic"
			(at 445.36 256.4 0)
			(layer "F.Fab")
			(hide yes)
			(effects
				(font
					(size 1 1)
					(thickness 0.15)
				)
			)
		)
		(property "Public" "False"
			(at 445.36 256.4 0)
			(layer "F.Fab")
			(hide yes)
			(effects
				(font
					(size 1 1)
					(thickness 0.15)
				)
			)
		)
		(property "Tolerance" ""
			(at 445.36 256.4 0)
			(layer "F.Fab")
			(hide yes)
			(effects
				(font
					(size 1 1)
					(thickness 0.15)
				)
			)
		)
		(property "Val" "0R"
			(at 445.36 256.4 0)
			(layer "F.Fab")
			(hide yes)
			(effects
				(font
					(size 1 1)
					(thickness 0.15)
				)
			)
		)
		(sheetname "PCIe misc")
		(sheetfile "pcie_misc.kicad_sch")
		(attr smd dnp)
		(fp_rect
			(start -0.925 -0.47)
			(end 0.925 0.47)
			(stroke
				(width 0.05)
				(type default)
			)
			(fill no)
			(layer "F.CrtYd")
		)
		(fp_rect
			(start -0.5 -0.25)
			(end 0.5 0.25)
			(stroke
				(width 0.15)
				(type solid)
			)
			(fill no)
			(layer "F.Fab")
		)
		(pad "1" smd roundrect
			(at -0.48 0 180)
			(size 0.59 0.64)
			(layers "F.Cu" "F.Mask" "F.Paste")
			(roundrect_rratio 0.25)
			(net 530 "/M.2 key M #2/~{CLKREQ}")
			(pintype "passive")
			(teardrops
				(best_length_ratio 0.2)
				(max_length 1)
				(best_width_ratio 0.9)
				(max_width 2)
				(curved_edges yes)
				(filter_ratio 0.9)
				(enabled yes)
				(allow_two_segments yes)
				(prefer_zone_connections yes)
			)
		)
		(pad "2" smd roundrect
			(at 0.48 0 180)
			(size 0.59 0.64)
			(layers "F.Cu" "F.Mask" "F.Paste")
			(roundrect_rratio 0.25)
			(net 606 "Net-(U37-~{OE4})")
			(pintype "passive")
			(teardrops
				(best_length_ratio 0.2)
				(max_length 1)
				(best_width_ratio 0.9)
				(max_width 2)
				(curved_edges yes)
				(filter_ratio 0.9)
				(enabled yes)
				(allow_two_segments yes)
				(prefer_zone_connections yes)
			)
		)
	)
	(footprint "antmicro-footprints:R_0402_1005Metric"
		(layer "F.Cu")
		(at 124.84 135.88 180)
		(descr "Resistor SMD 0402")
		(tags "resistor SMD 0402")
		(property "Reference" "R280"
			(at 0.79 -0.43 0)
			(layer "F.SilkS")
			(effects
				(font
					(size 0.7 0.7)
					(thickness 0.15)
				)
				(justify right bottom)
			)
		)
		(property "Value" "R_100k_0402"
			(at -1.011843 1.772047 0)
			(layer "F.Fab")
			(effects
				(font
					(size 0.7 0.7)
					(thickness 0.15)
				)
				(justify right bottom)
			)
		)
		(property "Datasheet" "https://www.bourns.com/docs/product-datasheets/cr.pdf"
			(at 0 0 180)
			(layer "F.Fab")
			(hide yes)
			(effects
				(font
					(size 1.27 1.27)
					(thickness 0.15)
				)
			)
		)
		(property "Author" "Antmicro"
			(at 249.68 271.76 0)
			(layer "F.Fab")
			(hide yes)
			(effects
				(font
					(size 1 1)
					(thickness 0.15)
				)
			)
		)
		(property "License" "Apache-2.0"
			(at 249.68 271.76 0)
			(layer "F.Fab")
			(hide yes)
			(effects
				(font
					(size 1 1)
					(thickness 0.15)
				)
			)
		)
		(property "MPN" "CR0402-FX-1003GLF"
			(at 249.68 271.76 0)
			(layer "F.Fab")
			(hide yes)
			(effects
				(font
					(size 1 1)
					(thickness 0.15)
				)
			)
		)
		(property "Manufacturer" "Bourns"
			(at 249.68 271.76 0)
			(layer "F.Fab")
			(hide yes)
			(effects
				(font
					(size 1 1)
					(thickness 0.15)
				)
			)
		)
		(property "Public" "False"
			(at 249.68 271.76 0)
			(layer "F.Fab")
			(hide yes)
			(effects
				(font
					(size 1 1)
					(thickness 0.15)
				)
			)
		)
		(property "Tolerance" "1%"
			(at 249.68 271.76 0)
			(layer "F.Fab")
			(hide yes)
			(effects
				(font
					(size 1 1)
					(thickness 0.15)
				)
			)
		)
		(property "Val" "100k"
			(at 249.68 271.76 0)
			(layer "F.Fab")
			(hide yes)
			(effects
				(font
					(size 1 1)
					(thickness 0.15)
				)
			)
		)
		(sheetname "KR to SFI #2")
		(sheetfile "kr_sfi.kicad_sch")
		(attr smd)
		(fp_rect
			(start -0.925 -0.47)
			(end 0.925 0.47)
			(stroke
				(width 0.05)
				(type default)
			)
			(fill no)
			(layer "F.CrtYd")
		)
		(fp_rect
			(start -0.5 -0.25)
			(end 0.5 0.25)
			(stroke
				(width 0.15)
				(type solid)
			)
			(fill no)
			(layer "F.Fab")
		)
		(pad "1" smd roundrect
			(at -0.48 0 180)
			(size 0.59 0.64)
			(layers "F.Cu" "F.Mask" "F.Paste")
			(roundrect_rratio 0.25)
			(net 2 "+3V3")
			(pintype "passive")
			(teardrops
				(best_length_ratio 0.2)
				(max_length 1)
				(best_width_ratio 0.9)
				(max_width 2)
				(curved_edges yes)
				(filter_ratio 0.9)
				(enabled yes)
				(allow_two_segments yes)
				(prefer_zone_connections yes)
			)
		)
		(pad "2" smd roundrect
			(at 0.48 0 180)
			(size 0.59 0.64)
			(layers "F.Cu" "F.Mask" "F.Paste")
			(roundrect_rratio 0.25)
			(net 668 "Net-(Y3-EN)")
			(pintype "passive")
			(teardrops
				(best_length_ratio 0.2)
				(max_length 1)
				(best_width_ratio 0.9)
				(max_width 2)
				(curved_edges yes)
				(filter_ratio 0.9)
				(enabled yes)
				(allow_two_segments yes)
				(prefer_zone_connections yes)
			)
		)
	)
	(footprint "antmicro-footprints:R_0402_1005Metric"
		(layer "F.Cu")
		(at 298.2 84.01 -90)
		(descr "Resistor SMD 0402")
		(tags "resistor SMD 0402")
		(property "Reference" "R127"
			(at 0.85 -0.45 90)
			(layer "F.SilkS")
			(effects
				(font
					(size 0.7 0.7)
					(thickness 0.15)
				)
				(justify right bottom)
			)
		)
		(property "Value" "R_10k_0402"
			(at -1.011843 1.772047 90)
			(layer "F.Fab")
			(effects
				(font
					(size 0.7 0.7)
					(thickness 0.15)
				)
				(justify right bottom)
			)
		)
		(property "Datasheet" "https://www.bourns.com/docs/product-datasheets/cr.pdf"
			(at 0 0 270)
			(layer "F.Fab")
			(hide yes)
			(effects
				(font
					(size 1.27 1.27)
					(thickness 0.15)
				)
			)
		)
		(property "Author" "Antmicro"
			(at 214.19 382.21 0)
			(layer "F.Fab")
			(hide yes)
			(effects
				(font
					(size 1 1)
					(thickness 0.15)
				)
			)
		)
		(property "License" "Apache-2.0"
			(at 214.19 382.21 0)
			(layer "F.Fab")
			(hide yes)
			(effects
				(font
					(size 1 1)
					(thickness 0.15)
				)
			)
		)
		(property "MPN" "CR0402-FX-1002GLF"
			(at 214.19 382.21 0)
			(layer "F.Fab")
			(hide yes)
			(effects
				(font
					(size 1 1)
					(thickness 0.15)
				)
			)
		)
		(property "Manufacturer" "Bourns"
			(at 214.19 382.21 0)
			(layer "F.Fab")
			(hide yes)
			(effects
				(font
					(size 1 1)
					(thickness 0.15)
				)
			)
		)
		(property "Public" "False"
			(at 214.19 382.21 0)
			(layer "F.Fab")
			(hide yes)
			(effects
				(font
					(size 1 1)
					(thickness 0.15)
				)
			)
		)
		(property "Tolerance" "1%"
			(at 214.19 382.21 0)
			(layer "F.Fab")
			(hide yes)
			(effects
				(font
					(size 1 1)
					(thickness 0.15)
				)
			)
		)
		(property "Val" "10k"
			(at 214.19 382.21 0)
			(layer "F.Fab")
			(hide yes)
			(effects
				(font
					(size 1 1)
					(thickness 0.15)
				)
			)
		)
		(sheetname "M.2 key M #2")
		(sheetfile "m2keym.kicad_sch")
		(attr smd dnp)
		(fp_rect
			(start -0.925 -0.47)
			(end 0.925 0.47)
			(stroke
				(width 0.05)
				(type default)
			)
			(fill no)
			(layer "F.CrtYd")
		)
		(fp_rect
			(start -0.5 -0.25)
			(end 0.5 0.25)
			(stroke
				(width 0.15)
				(type solid)
			)
			(fill no)
			(layer "F.Fab")
		)
		(pad "1" smd roundrect
			(at -0.48 0 270)
			(size 0.59 0.64)
			(layers "F.Cu" "F.Mask" "F.Paste")
			(roundrect_rratio 0.25)
			(net 270 "/M.2 key M #2/~{PERST_D}")
			(pintype "passive")
			(teardrops
				(best_length_ratio 0.2)
				(max_length 1)
				(best_width_ratio 0.9)
				(max_width 2)
				(curved_edges yes)
				(filter_ratio 0.9)
				(enabled yes)
				(allow_two_segments yes)
				(prefer_zone_connections yes)
			)
		)
		(pad "2" smd roundrect
			(at 0.48 0 270)
			(size 0.59 0.64)
			(layers "F.Cu" "F.Mask" "F.Paste")
			(roundrect_rratio 0.25)
			(net 2 "+3V3")
			(pintype "passive")
			(teardrops
				(best_length_ratio 0.2)
				(max_length 1)
				(best_width_ratio 0.9)
				(max_width 2)
				(curved_edges yes)
				(filter_ratio 0.9)
				(enabled yes)
				(allow_two_segments yes)
				(prefer_zone_connections yes)
			)
		)
	)
	(footprint "antmicro-footprints:R_0402_1005Metric"
		(layer "F.Cu")
		(at 314.075499 136.46 -90)
		(descr "Resistor SMD 0402")
		(tags "resistor SMD 0402")
		(property "Reference" "R112"
			(at -3.05 -5.574501 90)
			(layer "F.SilkS")
			(effects
				(font
					(size 0.7 0.7)
					(thickness 0.15)
				)
				(justify right bottom)
			)
		)
		(property "Value" "R_15k_0402"
			(at -1.011843 1.772047 90)
			(layer "F.Fab")
			(effects
				(font
					(size 0.7 0.7)
					(thickness 0.15)
				)
				(justify right bottom)
			)
		)
		(property "Datasheet" "https://www.bourns.com/docs/product-datasheets/cr.pdf"
			(at 0 0 270)
			(layer "F.Fab")
			(hide yes)
			(effects
				(font
					(size 1.27 1.27)
					(thickness 0.15)
				)
			)
		)
		(property "Author" "Antmicro"
			(at 177.615499 450.535499 0)
			(layer "F.Fab")
			(hide yes)
			(effects
				(font
					(size 1 1)
					(thickness 0.15)
				)
			)
		)
		(property "License" "Apache-2.0"
			(at 177.615499 450.535499 0)
			(layer "F.Fab")
			(hide yes)
			(effects
				(font
					(size 1 1)
					(thickness 0.15)
				)
			)
		)
		(property "MPN" "CR0402-FX-1502GLF"
			(at 177.615499 450.535499 0)
			(layer "F.Fab")
			(hide yes)
			(effects
				(font
					(size 1 1)
					(thickness 0.15)
				)
			)
		)
		(property "Manufacturer" "Bourns"
			(at 177.615499 450.535499 0)
			(layer "F.Fab")
			(hide yes)
			(effects
				(font
					(size 1 1)
					(thickness 0.15)
				)
			)
		)
		(property "Public" "False"
			(at 177.615499 450.535499 0)
			(layer "F.Fab")
			(hide yes)
			(effects
				(font
					(size 1 1)
					(thickness 0.15)
				)
			)
		)
		(property "Tolerance" "1%"
			(at 177.615499 450.535499 0)
			(layer "F.Fab")
			(hide yes)
			(effects
				(font
					(size 1 1)
					(thickness 0.15)
				)
			)
		)
		(property "Val" "15k"
			(at 177.615499 450.535499 0)
			(layer "F.Fab")
			(hide yes)
			(effects
				(font
					(size 1 1)
					(thickness 0.15)
				)
			)
		)
		(sheetname "Power")
		(sheetfile "power.kicad_sch")
		(attr smd)
		(fp_rect
			(start -0.925 -0.47)
			(end 0.925 0.47)
			(stroke
				(width 0.05)
				(type default)
			)
			(fill no)
			(layer "F.CrtYd")
		)
		(fp_rect
			(start -0.5 -0.25)
			(end 0.5 0.25)
			(stroke
				(width 0.15)
				(type solid)
			)
			(fill no)
			(layer "F.Fab")
		)
		(pad "1" smd roundrect
			(at -0.48 0 270)
			(size 0.59 0.64)
			(layers "F.Cu" "F.Mask" "F.Paste")
			(roundrect_rratio 0.25)
			(net 1 "GND")
			(pintype "passive")
			(teardrops
				(best_length_ratio 0.2)
				(max_length 1)
				(best_width_ratio 0.9)
				(max_width 2)
				(curved_edges yes)
				(filter_ratio 0.9)
				(enabled yes)
				(allow_two_segments yes)
				(prefer_zone_connections yes)
			)
		)
		(pad "2" smd roundrect
			(at 0.48 0 270)
			(size 0.59 0.64)
			(layers "F.Cu" "F.Mask" "F.Paste")
			(roundrect_rratio 0.25)
			(net 586 "Net-(U22-FB)")
			(pintype "passive")
			(teardrops
				(best_length_ratio 0.2)
				(max_length 1)
				(best_width_ratio 0.9)
				(max_width 2)
				(curved_edges yes)
				(filter_ratio 0.9)
				(enabled yes)
				(allow_two_segments yes)
				(prefer_zone_connections yes)
			)
		)
	)
	(footprint "antmicro-footprints:C_Pol_EIA-D"
		(layer "F.Cu")
		(at 313.95 140.26)
		(property "Reference" "C43"
			(at 1.15 -2.35 0)
			(layer "F.SilkS")
			(effects
				(font
					(size 0.7 0.7)
					(thickness 0.15)
				)
				(justify left bottom)
			)
		)
		(property "Value" "C_Pol_68u_16V_Panasonic-TQC-D"
			(at 0 3.4 0)
			(layer "F.Fab")
			(effects
				(font
					(size 0.7 0.7)
					(thickness 0.15)
				)
				(justify left bottom)
			)
		)
		(property "Datasheet" "https://industrial.panasonic.com/sa/products/pt/aluminum-cap-smd/models/16TQC68MYF"
			(at 0 0 0)
			(layer "F.Fab")
			(hide yes)
			(effects
				(font
					(size 1.27 1.27)
					(thickness 0.15)
				)
			)
		)
		(property "Author" "Antmicro"
			(at 0 0 0)
			(layer "F.Fab")
			(hide yes)
			(effects
				(font
					(size 1 1)
					(thickness 0.15)
				)
			)
		)
		(property "Dielectric" "template_dielectric"
			(at 0 0 0)
			(layer "F.Fab")
			(hide yes)
			(effects
				(font
					(size 1 1)
					(thickness 0.15)
				)
			)
		)
		(property "License" "Apache-2.0"
			(at 0 0 0)
			(layer "F.Fab")
			(hide yes)
			(effects
				(font
					(size 1 1)
					(thickness 0.15)
				)
			)
		)
		(property "MPN" "16TQC68MYF"
			(at 0 0 0)
			(layer "F.Fab")
			(hide yes)
			(effects
				(font
					(size 1 1)
					(thickness 0.15)
				)
			)
		)
		(property "Manufacturer" "Panasonic"
			(at 0 0 0)
			(layer "F.Fab")
			(hide yes)
			(effects
				(font
					(size 1 1)
					(thickness 0.15)
				)
			)
		)
		(property "Public" "False"
			(at 0 0 0)
			(layer "F.Fab")
			(hide yes)
			(effects
				(font
					(size 1 1)
					(thickness 0.15)
				)
			)
		)
		(property "Val" "68u"
			(at 0 0 0)
			(layer "F.Fab")
			(hide yes)
			(effects
				(font
					(size 1 1)
					(thickness 0.15)
				)
			)
		)
		(property "Voltage" "16V"
			(at 0 0 0)
			(layer "F.Fab")
			(hide yes)
			(effects
				(font
					(size 1 1)
					(thickness 0.15)
				)
			)
		)
		(sheetname "Power")
		(sheetfile "power.kicad_sch")
		(attr smd)
		(fp_line
			(start -4.3 -1.825)
			(end -3.9 -1.825)
			(stroke
				(width 0.12)
				(type solid)
			)
			(layer "F.SilkS")
		)
		(fp_line
			(start -4.1 -2.025)
			(end -4.1 -1.625)
			(stroke
				(width 0.12)
				(type solid)
			)
			(layer "F.SilkS")
		)
		(fp_line
			(start -3.58 -2.2)
			(end 3.6 -2.2)
			(stroke
				(width 0.15)
				(type solid)
			)
			(layer "F.SilkS")
		)
		(fp_line
			(start -3.58 -1.6)
			(end -3.58 -2.2)
			(stroke
				(width 0.15)
				(type solid)
			)
			(layer "F.SilkS")
		)
		(fp_line
			(start -3.58 2.2)
			(end -3.58 1.6)
			(stroke
				(width 0.15)
				(type solid)
			)
			(layer "F.SilkS")
		)
		(fp_line
			(start 3.6 -2.2)
			(end 3.6 -1.6)
			(stroke
				(width 0.15)
				(type solid)
			)
			(layer "F.SilkS")
		)
		(fp_line
			(start 3.6 1.6)
			(end 3.6 2.2)
			(stroke
				(width 0.15)
				(type solid)
			)
			(layer "F.SilkS")
		)
		(fp_line
			(start 3.6 2.2)
			(end -3.58 2.2)
			(stroke
				(width 0.15)
				(type solid)
			)
			(layer "F.SilkS")
		)
		(fp_line
			(start -4.505 1.51)
			(end -4.505 -1.5)
			(stroke
				(width 0.05)
				(type solid)
			)
			(layer "F.CrtYd")
		)
		(fp_line
			(start -3.775 -2.4)
			(end -3.775 -1.5)
			(stroke
				(width 0.05)
				(type solid)
			)
			(layer "F.CrtYd")
		)
		(fp_line
			(start -3.775 -2.4)
			(end 3.77 -2.4)
			(stroke
				(width 0.05)
				(type solid)
			)
			(layer "F.CrtYd")
		)
		(fp_line
			(start -3.775 -1.5)
			(end -4.505 -1.5)
			(stroke
				(width 0.05)
				(type solid)
			)
			(layer "F.CrtYd")
		)
		(fp_line
			(start -3.77 1.51)
			(end -4.505 1.51)
			(stroke
				(width 0.05)
				(type solid)
			)
			(layer "F.CrtYd")
		)
		(fp_line
			(start -3.77 2.4)
			(end -3.77 1.51)
			(stroke
				(width 0.05)
				(type solid)
			)
			(layer "F.CrtYd")
		)
		(fp_line
			(start 3.77 -2.4)
			(end 3.77 -1.51)
			(stroke
				(width 0.05)
				(type solid)
			)
			(layer "F.CrtYd")
		)
		(fp_line
			(start 3.77 -1.51)
			(end 4.505 -1.51)
			(stroke
				(width 0.05)
				(type solid)
			)
			(layer "F.CrtYd")
		)
		(fp_line
			(start 3.77 1.51)
			(end 3.77 2.4)
			(stroke
				(width 0.05)
				(type solid)
			)
			(layer "F.CrtYd")
		)
		(fp_line
			(start 3.77 2.4)
			(end -3.77 2.4)
			(stroke
				(width 0.05)
				(type solid)
			)
			(layer "F.CrtYd")
		)
		(fp_line
			(start 4.505 -1.51)
			(end 4.505 1.5)
			(stroke
				(width 0.05)
				(type solid)
			)
			(layer "F.CrtYd")
		)
		(fp_line
			(start 4.505 1.51)
			(end 3.77 1.51)
			(stroke
				(width 0.05)
				(type solid)
			)
			(layer "F.CrtYd")
		)
		(fp_rect
			(start -3.65 -2.15)
			(end 3.65 2.15)
			(stroke
				(width 0.15)
				(type solid)
			)
			(fill no)
			(layer "F.Fab")
		)
		(pad "1" smd roundrect
			(at -3.1 0)
			(size 2.31 2.52)
			(layers "F.Cu" "F.Mask" "F.Paste")
			(roundrect_rratio 0.1)
			(net 62 "+12V_AON")
			(pintype "passive")
			(teardrops
				(best_length_ratio 0.2)
				(max_length 1)
				(best_width_ratio 0.9)
				(max_width 2)
				(curved_edges yes)
				(filter_ratio 0.9)
				(enabled yes)
				(allow_two_segments yes)
				(prefer_zone_connections yes)
			)
		)
		(pad "2" smd roundrect
			(at 3.1 0)
			(size 2.31 2.52)
			(layers "F.Cu" "F.Mask" "F.Paste")
			(roundrect_rratio 0.1)
			(net 1 "GND")
			(pintype "passive")
			(teardrops
				(best_length_ratio 0.2)
				(max_length 1)
				(best_width_ratio 0.9)
				(max_width 2)
				(curved_edges yes)
				(filter_ratio 0.9)
				(enabled yes)
				(allow_two_segments yes)
				(prefer_zone_connections yes)
			)
		)
	)
)
